# S9S_MB_2U (Grand Teton) — schematic netlist excerpt (pin names and nets, part order shuffled) for the footprints in the layout excerpt that follows; sources: Cadence DE-HDL packaged netlist, KiCad conversion of 03242023_DA0F0TMBIJ0_F0T_Motherboard_J_brd_V01_OCP.brd

R3603  Q_RES  10 1% CHIP  pkg 0402LF  page 171 : A = P3V3_OCP_SFF ; B = VSENSE_P3V3_INA230_1_INN

PU207  MP5016GQHLZ  MP5016GQH-L-Z EMPTY  pkg QFN8_2X1-5  page 163
  VCC  = P3V3_AUX
  GND  = GND
  ILIMIT  = P3V3_OCP_ILIMIT_2
  MODE  = P3V3_OCP_MODE_2
  SOURCE  = P3V3_OCP_V3_2_R
  GATE  = P3V3_OCP_GATE_PU207_2
  EN  = P3V3_OCP_EN_2
  DV_DT  = P3V3_OCP_DVDT_2

C691  Q_CAP_DIFFBUS  DIFF BUS_0.22UF 6.3V 20% X6S  pkg C0201  page 177 : \1\ = P5E_CPU1_PE4_TX_C_DP<9> ; \2\ = P5E_CPU1_PE4_TX_DP<9>

(kicad_pcb
	(version 20260206)
	(generator "pcbnew")
	(generator_version "10.0")
	(general
		(thickness 1.6)
		(legacy_teardrops no)
	)
	(paper "A4")
	(title_block
		(title "03242023_DA0F0TMBIJ0_F0T_Motherboard_J_brd_V01_OCP.brd")
		(comment 1 "Grand Teton / footprints 404-406 of 6105")
	)
	(layers
		(0 "F.Cu" signal "TOP")
		(4 "In1.Cu" signal "GND")
		(6 "In2.Cu" signal "IN1")
		(8 "In3.Cu" signal "GND1")
		(10 "In4.Cu" signal "IN2")
		(12 "In5.Cu" signal "GND2")
		(14 "In6.Cu" signal "IN3")
		(16 "In7.Cu" signal "GND3")
		(18 "In8.Cu" signal "VCC")
		(20 "In9.Cu" signal "VCC1")
		(22 "In10.Cu" signal "GND4")
		(24 "In11.Cu" signal "IN4")
		(26 "In12.Cu" signal "GND5")
		(28 "In13.Cu" signal "IN5")
		(30 "In14.Cu" signal "GND6")
		(32 "In15.Cu" signal "IN6")
		(34 "In16.Cu" signal "GND7")
		(2 "B.Cu" signal "BOTTOM")
		(9 "F.Adhes" user "F.Adhesive")
		(11 "B.Adhes" user "B.Adhesive")
		(13 "F.Paste" user "Package Geometry/Pastemask Top")
		(15 "B.Paste" user "Package Geometry/Pastemask Bottom")
		(5 "F.SilkS" user "Ref Des/Silkscreen Top")
		(7 "B.SilkS" user "Ref Des/Silkscreen Bottom")
		(1 "F.Mask" user "Board Geometry/Soldermask Top")
		(3 "B.Mask" user "Board Geometry/Soldermask Bottom")
		(17 "Dwgs.User" user "User.Drawings")
		(19 "Cmts.User" user "User.Comments")
		(21 "Eco1.User" user "User.Eco1")
		(23 "Eco2.User" user "User.Eco2")
		(25 "Edge.Cuts" user "Board Geometry/Outline")
		(27 "Margin" user)
		(31 "F.CrtYd" user "Package Geometry/Place Bound Top")
		(29 "B.CrtYd" user "Package Geometry/Place Bound Bottom")
		(35 "F.Fab" user "Ref Des/Assembly Top")
		(33 "B.Fab" user "Ref Des/Assembly Bottom")
	)
	(footprint ""
		(layer "F.Cu")
		(at 69.02196 -57.094628)
		(property "Reference" "PU207"
			(at -5.23748 1.086612 0)
			(unlocked yes)
			(layer "F.SilkS")
			(effects
				(font
					(size 0.7874 0.5842)
					(thickness 0.1524)
				)
			)
		)
		(property "Value" ""
			(at 0 0 0)
			(layer "F.Fab")
			(effects
				(font
					(size 1.27 1.27)
				)
			)
		)
		(duplicate_pad_numbers_are_jumpers no)
		(fp_line
			(start -1.239774 -1.495298)
			(end 1.239774 -1.495298)
			(stroke
				(width 0.1524)
				(type default)
			)
			(layer "F.SilkS")
		)
		(fp_line
			(start -1.239774 1.495298)
			(end -1.239774 -1.495298)
			(stroke
				(width 0.1524)
				(type default)
			)
			(layer "F.SilkS")
		)
		(fp_line
			(start 1.239774 -1.495298)
			(end 1.239774 1.495298)
			(stroke
				(width 0.1524)
				(type default)
			)
			(layer "F.SilkS")
		)
		(fp_line
			(start 1.239774 1.495298)
			(end -1.239774 1.495298)
			(stroke
				(width 0.1524)
				(type default)
			)
			(layer "F.SilkS")
		)
		(fp_poly
			(pts
				(xy -2.525014 -1.62814) (xy -1.509014 -1.12014) (xy -2.525014 -0.61214)
			)
			(stroke
				(width 0)
				(type default)
			)
			(fill yes)
			(layer "F.SilkS")
		)
		(fp_line
			(start -0.8001 -1.050036)
			(end 0.8001 -1.050036)
			(stroke
				(width 0.1)
				(type default)
			)
			(layer "F.Fab")
		)
		(fp_line
			(start -0.8001 1.050036)
			(end -0.8001 -1.050036)
			(stroke
				(width 0.1)
				(type default)
			)
			(layer "F.Fab")
		)
		(fp_line
			(start 0.8001 -1.050036)
			(end 0.8001 1.050036)
			(stroke
				(width 0.1)
				(type default)
			)
			(layer "F.Fab")
		)
		(fp_line
			(start 0.8001 1.050036)
			(end -0.8001 1.050036)
			(stroke
				(width 0.1)
				(type default)
			)
			(layer "F.Fab")
		)
		(fp_poly
			(pts
				(xy -2.458974 -0.508) (xy -2.458974 0.508) (xy -1.442974 0)
			)
			(stroke
				(width 0)
				(type default)
			)
			(fill yes)
			(layer "F.Fab")
		)
		(pad "1_2" smd circle
			(at -0.374904 0 90)
			(size 0 0)
			(layers "F.Cu" "F.Mask" "F.Paste")
			(net "P3V3_AUX")
		)
		(pad "3" smd rect
			(at -0.499872 0.999998)
			(size 0.254 0.7112)
			(layers "F.Cu" "F.Mask" "F.Paste")
			(net "GND")
		)
		(pad "4" smd rect
			(at 0 0.999998)
			(size 0.254 0.7112)
			(layers "F.Cu" "F.Mask" "F.Paste")
			(net "P3V3_OCP_ILIMIT_2")
		)
		(pad "5" smd rect
			(at 0.499872 0.999998)
			(size 0.254 0.7112)
			(layers "F.Cu" "F.Mask" "F.Paste")
			(net "P3V3_OCP_MODE_2")
		)
		(pad "6_7" smd circle
			(at 0.374904 0 270)
			(size 0 0)
			(layers "F.Cu" "F.Mask" "F.Paste")
			(net "P3V3_OCP_V3_2_R")
		)
		(pad "8" smd rect
			(at 0.499872 -0.999998)
			(size 0.254 0.7112)
			(layers "F.Cu" "F.Mask" "F.Paste")
			(net "P3V3_OCP_GATE_PU207_2")
		)
		(pad "9" smd rect
			(at 0 -0.999998)
			(size 0.254 0.7112)
			(layers "F.Cu" "F.Mask" "F.Paste")
			(net "P3V3_OCP_EN_2")
		)
		(pad "10" smd rect
			(at -0.499872 -0.999998)
			(size 0.254 0.7112)
			(layers "F.Cu" "F.Mask" "F.Paste")
			(net "P3V3_OCP_DVDT_2")
		)
	)
	(footprint ""
		(layer "F.Cu")
		(at 77.784198 -408.517344 -90)
		(property "Reference" "C691"
			(at 0 0 270)
			(layer "F.SilkS")
			(hide yes)
			(effects
				(font
					(size 1.27 1.27)
				)
			)
		)
		(property "Value" ""
			(at 0 0 270)
			(layer "F.Fab")
			(effects
				(font
					(size 1.27 1.27)
				)
			)
		)
		(duplicate_pad_numbers_are_jumpers no)
		(fp_line
			(start -0.299974 0.150114)
			(end -0.299974 -0.150114)
			(stroke
				(width 0.1)
				(type default)
			)
			(layer "F.Fab")
		)
		(fp_line
			(start 0.299974 0.150114)
			(end -0.299974 0.150114)
			(stroke
				(width 0.1)
				(type default)
			)
			(layer "F.Fab")
		)
		(fp_line
			(start -0.299974 -0.150114)
			(end 0.299974 -0.150114)
			(stroke
				(width 0.1)
				(type default)
			)
			(layer "F.Fab")
		)
		(fp_line
			(start 0.299974 -0.150114)
			(end 0.299974 0.150114)
			(stroke
				(width 0.1)
				(type default)
			)
			(layer "F.Fab")
		)
		(pad "1" smd rect
			(at -0.2667 0 270)
			(size 0.3048 0.381)
			(layers "F.Cu" "F.Mask" "F.Paste")
			(net "P5E_CPU1_PE4_TX_C_DP<9>")
		)
		(pad "2" smd rect
			(at 0.2667 0 270)
			(size 0.3048 0.381)
			(layers "F.Cu" "F.Mask" "F.Paste")
			(net "P5E_CPU1_PE4_TX_DP<9>")
		)
	)
	(footprint ""
		(layer "F.Cu")
		(at 432.636676 -94.938342)
		(property "Reference" "R3603"
			(at 0 0 0)
			(layer "F.SilkS")
			(hide yes)
			(effects
				(font
					(size 1.27 1.27)
				)
			)
		)
		(property "Value" ""
			(at 0 0 0)
			(layer "F.Fab")
			(effects
				(font
					(size 1.27 1.27)
				)
			)
		)
		(duplicate_pad_numbers_are_jumpers no)
		(fp_line
			(start -0.7874 -0.4064)
			(end 0.7874 -0.4064)
			(stroke
				(width 0.1524)
				(type default)
			)
			(layer "F.SilkS")
		)
		(fp_line
			(start -0.7874 0.4064)
			(end -0.7874 -0.4064)
			(stroke
				(width 0.1524)
				(type default)
			)
			(layer "F.SilkS")
		)
		(fp_line
			(start 0.7874 -0.4064)
			(end 0.7874 0.4064)
			(stroke
				(width 0.1524)
				(type default)
			)
			(layer "F.SilkS")
		)
		(fp_line
			(start 0.7874 0.4064)
			(end -0.7874 0.4064)
			(stroke
				(width 0.1524)
				(type default)
			)
			(layer "F.SilkS")
		)
		(fp_line
			(start -0.67945 -0.305054)
			(end -0.12065 -0.305054)
			(stroke
				(width 0.1)
				(type default)
			)
			(layer "F.Fab")
		)
		(fp_line
			(start -0.67945 0.3048)
			(end -0.67945 -0.305054)
			(stroke
				(width 0.1)
				(type default)
			)
			(layer "F.Fab")
		)
		(fp_line
			(start -0.12065 -0.305054)
			(end -0.12065 -0.2794)
			(stroke
				(width 0.1)
				(type default)
			)
			(layer "F.Fab")
		)
		(fp_line
			(start -0.12065 -0.2794)
			(end 0.12065 -0.2794)
			(stroke
				(width 0.1)
				(type default)
			)
			(layer "F.Fab")
		)
		(fp_line
			(start -0.12065 0.2794)
			(end -0.12065 0.3048)
			(stroke
				(width 0.1)
				(type default)
			)
			(layer "F.Fab")
		)
		(fp_line
			(start -0.12065 0.3048)
			(end -0.67945 0.3048)
			(stroke
				(width 0.1)
				(type default)
			)
			(layer "F.Fab")
		)
		(fp_line
			(start 0.120396 0.2794)
			(end -0.12065 0.2794)
			(stroke
				(width 0.1)
				(type default)
			)
			(layer "F.Fab")
		)
		(fp_line
			(start 0.120396 0.3048)
			(end 0.120396 0.2794)
			(stroke
				(width 0.1)
				(type default)
			)
			(layer "F.Fab")
		)
		(fp_line
			(start 0.12065 -0.3048)
			(end 0.67945 -0.3048)
			(stroke
				(width 0.1)
				(type default)
			)
			(layer "F.Fab")
		)
		(fp_line
			(start 0.12065 -0.2794)
			(end 0.12065 -0.3048)
			(stroke
				(width 0.1)
				(type default)
			)
			(layer "F.Fab")
		)
		(fp_line
			(start 0.67945 -0.3048)
			(end 0.67945 0.3048)
			(stroke
				(width 0.1)
				(type default)
			)
			(layer "F.Fab")
		)
		(fp_line
			(start 0.67945 0.3048)
			(end 0.120396 0.3048)
			(stroke
				(width 0.1)
				(type default)
			)
			(layer "F.Fab")
		)
		(pad "1" smd circle
			(at -0.40005 0)
			(size 0 0)
			(layers "F.Cu" "F.Mask" "F.Paste")
			(net "P3V3_OCP_SFF")
		)
		(pad "2" smd circle
			(at 0.40005 0)
			(size 0 0)
			(layers "F.Cu" "F.Mask" "F.Paste")
			(net "VSENSE_P3V3_INA230_1_INN")
		)
	)
)
